(kicad_pcb
	(version 20260206)
	(generator "pcbnew")
	(generator_version "10.0")
	(general
		(thickness 1.6)
		(legacy_teardrops no)
	)
	(paper "A4")
	(title_block
		(title "v1-chassis-manager — T6M_CM_d_v01_1031_1645.brd")
		(comment 1 "Open CloudServer (Microsoft) / footprints 1925-1934 of 2512")
	)
	(layers
		(0 "F.Cu" signal "TOP")
		(4 "In1.Cu" signal "GND1")
		(6 "In2.Cu" signal "IN1")
		(8 "In3.Cu" signal "VCC1")
		(10 "In4.Cu" signal "VCC2")
		(12 "In5.Cu" signal "GND2")
		(14 "In6.Cu" signal "IN2")
		(16 "In7.Cu" signal "IN3")
		(18 "In8.Cu" signal "GND3")
		(2 "B.Cu" signal "BOTTOM")
		(9 "F.Adhes" user "F.Adhesive")
		(11 "B.Adhes" user "B.Adhesive")
		(13 "F.Paste" user "Package Geometry/Pastemask Top")
		(15 "B.Paste" user "Package Geometry/Pastemask Bottom")
		(5 "F.SilkS" user "Ref Des/Silkscreen Top")
		(7 "B.SilkS" user "Ref Des/Silkscreen Bottom")
		(1 "F.Mask" user "Board Geometry/Soldermask Top")
		(3 "B.Mask" user "Board Geometry/Soldermask Bottom")
		(17 "Dwgs.User" user "User.Drawings")
		(19 "Cmts.User" user "User.Comments")
		(21 "Eco1.User" user "User.Eco1")
		(23 "Eco2.User" user "User.Eco2")
		(25 "Edge.Cuts" user "Board Geometry/Outline")
		(27 "Margin" user)
		(31 "F.CrtYd" user "Package Geometry/Place Bound Top")
		(29 "B.CrtYd" user "Package Geometry/Place Bound Bottom")
		(35 "F.Fab" user "Ref Des/Assembly Top")
		(33 "B.Fab" user "Ref Des/Assembly Bottom")
	)
	(footprint ""
		(layer "B.Cu")
		(at 91.47302 -72.216518)
		(property "Reference" "R165"
			(at 4.07797 0.606044 0)
			(unlocked yes)
			(layer "B.SilkS")
			(effects
				(font
					(size 0.7874 0.5842)
					(thickness 0.1524)
				)
				(justify left mirror)
			)
		)
		(property "Value" ""
			(at 0 0 0)
			(layer "B.Fab")
			(effects
				(font
					(size 1.27 1.27)
				)
				(justify mirror)
			)
		)
		(duplicate_pad_numbers_are_jumpers no)
		(fp_line
			(start -0.7874 -0.4064)
			(end -0.7874 0.4064)
			(stroke
				(width 0.1524)
				(type default)
			)
			(layer "B.SilkS")
		)
		(fp_line
			(start -0.7874 0.4064)
			(end 0.7874 0.4064)
			(stroke
				(width 0.1524)
				(type default)
			)
			(layer "B.SilkS")
		)
		(fp_line
			(start 0.7874 -0.4064)
			(end -0.7874 -0.4064)
			(stroke
				(width 0.1524)
				(type default)
			)
			(layer "B.SilkS")
		)
		(fp_line
			(start 0.7874 0.4064)
			(end 0.7874 -0.4064)
			(stroke
				(width 0.1524)
				(type default)
			)
			(layer "B.SilkS")
		)
		(fp_poly
			(pts
				(xy 0.508 0.2794) (xy 0.508 0.2286) (xy 0.635 0.2286) (xy 0.635 -0.254) (xy 0.5334 -0.254) (xy 0.5334 -0.2794)
				(xy -0.5334 -0.2794) (xy -0.5334 -0.254) (xy -0.635 -0.254) (xy -0.635 0.254) (xy -0.5334 0.254)
				(xy -0.5334 0.2794)
			)
			(stroke
				(width 0)
				(type default)
			)
			(fill no)
			(layer "B.CrtYd")
		)
		(pad "1" smd rect
			(at -0.40005 0 180)
			(size 0.4572 0.508)
			(layers "B.Cu" "B.Mask" "B.Paste")
			(net "PD_CPU_NODE1_PUNIT_ST_ADDR0")
		)
		(pad "2" smd rect
			(at 0.40005 0 180)
			(size 0.4572 0.508)
			(layers "B.Cu" "B.Mask" "B.Paste")
			(net "P1V05_SUS_NODE1")
		)
	)
	(footprint ""
		(layer "B.Cu")
		(at 70.50786 -147.25269 180)
		(property "Reference" "PJ19"
			(at 0.933958 -0.877824 270)
			(unlocked yes)
			(layer "B.SilkS")
			(effects
				(font
					(size 0.7874 0.5842)
					(thickness 0.1524)
				)
				(justify left mirror)
			)
		)
		(property "Value" ""
			(at 0 0 0)
			(layer "B.Fab")
			(effects
				(font
					(size 1.27 1.27)
				)
				(justify mirror)
			)
		)
		(duplicate_pad_numbers_are_jumpers no)
		(fp_poly
			(pts
				(xy -0.2794 0.907796) (xy -0.254 0.907796) (xy -0.254 1.0414) (xy 0.254 1.0414) (xy 0.254 1.034796)
				(xy 0.254 0.933196) (xy 0.2794 0.933196) (xy 0.2794 -0.133604) (xy 0.254 -0.133604) (xy 0.254 -0.235204)
				(xy -0.254 -0.235204) (xy -0.254 -0.133604) (xy -0.2794 -0.133604)
			)
			(stroke
				(width 0)
				(type default)
			)
			(fill no)
			(layer "B.CrtYd")
		)
		(pad "1" smd custom
			(at 0 -0.000254)
			(size 0.127 0.127)
			(layers "B.Cu" "B.Mask" "B.Paste")
			(net "BMC_DEBUG_TXD")
			(options
				(clearance outline)
				(anchor circle)
			)
			(primitives
				(gr_poly
					(pts
						(xy -0.127 -0.508) (xy -0.127 0.0508) (xy -0.254 0.0508) (xy -0.254 0.508) (xy 0.254 0.508) (xy 0.254 0.0508)
						(xy 0.127 0.0508) (xy 0.127 -0.508)
					)
					(width 0)
					(fill yes)
				)
			)
		)
		(pad "2" smd rect
			(at 0 0.799846 270)
			(size 0.4572 0.508)
			(layers "B.Cu" "B.Mask" "B.Paste")
			(net "Net_467")
		)
		(zone
			(layer "B.Cu")
			(hatch none 0.5)
			(connect_pads
				(clearance 0)
			)
			(min_thickness 0.25)
			(keepout
				(tracks allowed)
				(vias not_allowed)
				(pads allowed)
				(copperpour not_allowed)
				(footprints allowed)
			)
			(placement
				(enabled no)
				(sheetname "")
			)
			(fill
				(thermal_gap 0.5)
				(thermal_bridge_width 0.5)
				(island_removal_mode 0)
			)
			(polygon
				(pts
					(xy 70.20306 -148.338286) (xy 70.81266 -148.338286) (xy 70.81266 -146.966686) (xy 70.20306 -146.966686)
				)
			)
		)
	)
	(footprint ""
		(layer "B.Cu")
		(at 118.184422 -123.297442 -90)
		(property "Reference" "PC93"
			(at -3.082036 0.88138 270)
			(unlocked yes)
			(layer "B.SilkS")
			(effects
				(font
					(size 0.7874 0.5842)
					(thickness 0.1524)
				)
				(justify left mirror)
			)
		)
		(property "Value" ""
			(at 0 0 90)
			(layer "B.Fab")
			(effects
				(font
					(size 1.27 1.27)
				)
				(justify mirror)
			)
		)
		(duplicate_pad_numbers_are_jumpers no)
		(fp_line
			(start -2.2098 0.9398)
			(end 2.2098 0.9398)
			(stroke
				(width 0.1524)
				(type default)
			)
			(layer "B.SilkS")
		)
		(fp_line
			(start 2.2098 0.9398)
			(end 2.2098 -0.9398)
			(stroke
				(width 0.1524)
				(type default)
			)
			(layer "B.SilkS")
		)
		(fp_line
			(start -2.2098 -0.9398)
			(end -2.2098 0.9398)
			(stroke
				(width 0.1524)
				(type default)
			)
			(layer "B.SilkS")
		)
		(fp_line
			(start 0 -0.9398)
			(end 0 0.9398)
			(stroke
				(width 0.1524)
				(type default)
			)
			(layer "B.SilkS")
		)
		(fp_line
			(start 2.2098 -0.9398)
			(end -2.2098 -0.9398)
			(stroke
				(width 0.1524)
				(type default)
			)
			(layer "B.SilkS")
		)
		(fp_poly
			(pts
				(xy 1.6764 0.889) (xy 1.6764 0.7874) (xy 2.0574 0.7874) (xy 2.0574 -0.7874) (xy 1.6764 -0.7874)
				(xy 1.6764 -0.9398) (xy -1.6764 -0.9398) (xy -1.6764 -0.7874) (xy -2.0574 -0.7874) (xy -2.0574 0.7874)
				(xy -1.6764 0.7874) (xy -1.6764 0.9398) (xy 1.6764 0.9398)
			)
			(stroke
				(width 0)
				(type default)
			)
			(fill no)
			(layer "B.CrtYd")
		)
		(fp_line
			(start -1.700022 0.899922)
			(end 1.700022 0.899922)
			(stroke
				(width 0.1)
				(type default)
			)
			(layer "B.Fab")
		)
		(fp_line
			(start 1.700022 0.899922)
			(end 1.700022 -0.899922)
			(stroke
				(width 0.1)
				(type default)
			)
			(layer "B.Fab")
		)
		(fp_line
			(start -1.700022 -0.899922)
			(end -1.700022 0.899922)
			(stroke
				(width 0.1)
				(type default)
			)
			(layer "B.Fab")
		)
		(fp_line
			(start 1.700022 -0.899922)
			(end -1.700022 -0.899922)
			(stroke
				(width 0.1)
				(type default)
			)
			(layer "B.Fab")
		)
		(pad "1" smd rect
			(at -1.4732 0 90)
			(size 1.1684 1.5748)
			(layers "B.Cu" "B.Mask" "B.Paste")
			(net "SW_VR_PVCCP_NODE1_VIN_FLT")
		)
		(pad "2" smd rect
			(at 1.4732 0 90)
			(size 1.1684 1.5748)
			(layers "B.Cu" "B.Mask" "B.Paste")
			(net "GND")
		)
	)
	(footprint ""
		(layer "B.Cu")
		(at 74.123296 -21.14296 90)
		(property "Reference" "C171"
			(at -5.852668 -0.810006 270)
			(unlocked yes)
			(layer "B.SilkS")
			(effects
				(font
					(size 0.7874 0.5842)
					(thickness 0.1524)
				)
				(justify left mirror)
			)
		)
		(property "Value" ""
			(at 0 0 90)
			(layer "B.Fab")
			(effects
				(font
					(size 1.27 1.27)
				)
				(justify mirror)
			)
		)
		(duplicate_pad_numbers_are_jumpers no)
		(fp_line
			(start 0.7874 -0.4064)
			(end -0.7874 -0.4064)
			(stroke
				(width 0.1524)
				(type default)
			)
			(layer "B.SilkS")
		)
		(fp_line
			(start -0.7874 -0.4064)
			(end -0.7874 0.4064)
			(stroke
				(width 0.1524)
				(type default)
			)
			(layer "B.SilkS")
		)
		(fp_line
			(start 0 0.381)
			(end 0 -0.381)
			(stroke
				(width 0.1524)
				(type default)
			)
			(layer "B.SilkS")
		)
		(fp_line
			(start 0.7874 0.4064)
			(end 0.7874 -0.4064)
			(stroke
				(width 0.1524)
				(type default)
			)
			(layer "B.SilkS")
		)
		(fp_line
			(start -0.7874 0.4064)
			(end 0.7874 0.4064)
			(stroke
				(width 0.1524)
				(type default)
			)
			(layer "B.SilkS")
		)
		(fp_poly
			(pts
				(xy 0.5334 0.254) (xy 0.635 0.254) (xy 0.635 0.2286) (xy 0.635 -0.254) (xy 0.5334 -0.254) (xy 0.5334 -0.2794)
				(xy -0.5334 -0.2794) (xy -0.5334 -0.254) (xy -0.635 -0.254) (xy -0.635 0.254) (xy -0.5334 0.254)
				(xy -0.5334 0.2794) (xy 0.508 0.2794) (xy 0.5334 0.2794)
			)
			(stroke
				(width 0)
				(type default)
			)
			(fill no)
			(layer "B.CrtYd")
		)
		(pad "1" smd rect
			(at -0.40005 0 270)
			(size 0.4572 0.508)
			(layers "B.Cu" "B.Mask" "B.Paste")
			(net "PV_VDDR_NODE1")
		)
		(pad "2" smd rect
			(at 0.40005 0 270)
			(size 0.4572 0.508)
			(layers "B.Cu" "B.Mask" "B.Paste")
			(net "GND")
		)
	)
	(footprint ""
		(layer "B.Cu")
		(at 132.41528 -43.7134 -90)
		(property "Reference" "R1329"
			(at 2.8194 -0.93345 270)
			(unlocked yes)
			(layer "B.SilkS")
			(effects
				(font
					(size 0.7874 0.5842)
					(thickness 0.1524)
				)
				(justify left mirror)
			)
		)
		(property "Value" ""
			(at 0 0 90)
			(layer "B.Fab")
			(effects
				(font
					(size 1.27 1.27)
				)
				(justify mirror)
			)
		)
		(duplicate_pad_numbers_are_jumpers no)
		(fp_line
			(start -0.7874 0.4064)
			(end 0.7874 0.4064)
			(stroke
				(width 0.1524)
				(type default)
			)
			(layer "B.SilkS")
		)
		(fp_line
			(start 0.7874 0.4064)
			(end 0.7874 -0.4064)
			(stroke
				(width 0.1524)
				(type default)
			)
			(layer "B.SilkS")
		)
		(fp_line
			(start -0.7874 -0.4064)
			(end -0.7874 0.4064)
			(stroke
				(width 0.1524)
				(type default)
			)
			(layer "B.SilkS")
		)
		(fp_line
			(start 0.7874 -0.4064)
			(end -0.7874 -0.4064)
			(stroke
				(width 0.1524)
				(type default)
			)
			(layer "B.SilkS")
		)
		(fp_poly
			(pts
				(xy 0.508 0.2794) (xy 0.508 0.2286) (xy 0.635 0.2286) (xy 0.635 -0.254) (xy 0.5334 -0.254) (xy 0.5334 -0.2794)
				(xy -0.5334 -0.2794) (xy -0.5334 -0.254) (xy -0.635 -0.254) (xy -0.635 0.254) (xy -0.5334 0.254)
				(xy -0.5334 0.2794)
			)
			(stroke
				(width 0)
				(type default)
			)
			(fill no)
			(layer "B.CrtYd")
		)
		(pad "1" smd rect
			(at -0.40005 0 90)
			(size 0.4572 0.508)
			(layers "B.Cu" "B.Mask" "B.Paste")
			(net "UART_RI_P4_N")
		)
		(pad "2" smd rect
			(at 0.40005 0 90)
			(size 0.4572 0.508)
			(layers "B.Cu" "B.Mask" "B.Paste")
			(net "P3V3_NODE1")
		)
	)
	(footprint ""
		(layer "B.Cu")
		(at 90.81262 -168.942512 180)
		(property "Reference" "C568"
			(at -24.86914 -19.97075 0)
			(unlocked yes)
			(layer "B.SilkS")
			(effects
				(font
					(size 0.7874 0.5842)
					(thickness 0.1524)
				)
				(justify left mirror)
			)
		)
		(property "Value" ""
			(at 0 0 0)
			(layer "B.Fab")
			(effects
				(font
					(size 1.27 1.27)
				)
				(justify mirror)
			)
		)
		(duplicate_pad_numbers_are_jumpers no)
		(fp_line
			(start 0.7874 0.4064)
			(end 0.7874 -0.4064)
			(stroke
				(width 0.1524)
				(type default)
			)
			(layer "B.SilkS")
		)
		(fp_line
			(start 0.7874 -0.4064)
			(end -0.7874 -0.4064)
			(stroke
				(width 0.1524)
				(type default)
			)
			(layer "B.SilkS")
		)
		(fp_line
			(start 0 0.381)
			(end 0 -0.381)
			(stroke
				(width 0.1524)
				(type default)
			)
			(layer "B.SilkS")
		)
		(fp_line
			(start -0.7874 0.4064)
			(end 0.7874 0.4064)
			(stroke
				(width 0.1524)
				(type default)
			)
			(layer "B.SilkS")
		)
		(fp_line
			(start -0.7874 -0.4064)
			(end -0.7874 0.4064)
			(stroke
				(width 0.1524)
				(type default)
			)
			(layer "B.SilkS")
		)
		(fp_poly
			(pts
				(xy 0.5334 0.254) (xy 0.635 0.254) (xy 0.635 0.2286) (xy 0.635 -0.254) (xy 0.5334 -0.254) (xy 0.5334 -0.2794)
				(xy -0.5334 -0.2794) (xy -0.5334 -0.254) (xy -0.635 -0.254) (xy -0.635 0.254) (xy -0.5334 0.254)
				(xy -0.5334 0.2794) (xy 0.508 0.2794) (xy 0.5334 0.2794)
			)
			(stroke
				(width 0)
				(type default)
			)
			(fill no)
			(layer "B.CrtYd")
		)
		(pad "1" smd rect
			(at -0.40005 0)
			(size 0.4572 0.508)
			(layers "B.Cu" "B.Mask" "B.Paste")
			(net "GND")
		)
		(pad "2" smd rect
			(at 0.40005 0)
			(size 0.4572 0.508)
			(layers "B.Cu" "B.Mask" "B.Paste")
			(net "P3V3_NODE1")
		)
	)
	(footprint ""
		(layer "B.Cu")
		(at 137.970006 -35.41141)
		(property "Reference" "R1184"
			(at -4.172458 18.515838 0)
			(unlocked yes)
			(layer "B.SilkS")
			(effects
				(font
					(size 0.7874 0.5842)
					(thickness 0.1524)
				)
				(justify left mirror)
			)
		)
		(property "Value" ""
			(at 0 0 0)
			(layer "B.Fab")
			(effects
				(font
					(size 1.27 1.27)
				)
				(justify mirror)
			)
		)
		(duplicate_pad_numbers_are_jumpers no)
		(fp_line
			(start -0.7874 -0.4064)
			(end -0.7874 0.4064)
			(stroke
				(width 0.1524)
				(type default)
			)
			(layer "B.SilkS")
		)
		(fp_line
			(start -0.7874 0.4064)
			(end 0.7874 0.4064)
			(stroke
				(width 0.1524)
				(type default)
			)
			(layer "B.SilkS")
		)
		(fp_line
			(start 0.7874 -0.4064)
			(end -0.7874 -0.4064)
			(stroke
				(width 0.1524)
				(type default)
			)
			(layer "B.SilkS")
		)
		(fp_line
			(start 0.7874 0.4064)
			(end 0.7874 -0.4064)
			(stroke
				(width 0.1524)
				(type default)
			)
			(layer "B.SilkS")
		)
		(fp_poly
			(pts
				(xy 0.508 0.2794) (xy 0.508 0.2286) (xy 0.635 0.2286) (xy 0.635 -0.254) (xy 0.5334 -0.254) (xy 0.5334 -0.2794)
				(xy -0.5334 -0.2794) (xy -0.5334 -0.254) (xy -0.635 -0.254) (xy -0.635 0.254) (xy -0.5334 0.254)
				(xy -0.5334 0.2794)
			)
			(stroke
				(width 0)
				(type default)
			)
			(fill no)
			(layer "B.CrtYd")
		)
		(pad "1" smd rect
			(at -0.40005 0 180)
			(size 0.4572 0.508)
			(layers "B.Cu" "B.Mask" "B.Paste")
			(net "SIO_CPLD_RSV2_R")
		)
		(pad "2" smd rect
			(at 0.40005 0 180)
			(size 0.4572 0.508)
			(layers "B.Cu" "B.Mask" "B.Paste")
			(net "GND")
		)
	)
	(footprint ""
		(layer "B.Cu")
		(at 50.273966 -84.077556 180)
		(property "Reference" "R148"
			(at 13.842746 -30.57652 0)
			(unlocked yes)
			(layer "B.SilkS")
			(effects
				(font
					(size 0.7874 0.5842)
					(thickness 0.1524)
				)
				(justify left mirror)
			)
		)
		(property "Value" ""
			(at 0 0 0)
			(layer "B.Fab")
			(effects
				(font
					(size 1.27 1.27)
				)
				(justify mirror)
			)
		)
		(duplicate_pad_numbers_are_jumpers no)
		(fp_line
			(start 0.7874 0.4064)
			(end 0.7874 -0.4064)
			(stroke
				(width 0.1524)
				(type default)
			)
			(layer "B.SilkS")
		)
		(fp_line
			(start 0.7874 -0.4064)
			(end -0.7874 -0.4064)
			(stroke
				(width 0.1524)
				(type default)
			)
			(layer "B.SilkS")
		)
		(fp_line
			(start -0.7874 0.4064)
			(end 0.7874 0.4064)
			(stroke
				(width 0.1524)
				(type default)
			)
			(layer "B.SilkS")
		)
		(fp_line
			(start -0.7874 -0.4064)
			(end -0.7874 0.4064)
			(stroke
				(width 0.1524)
				(type default)
			)
			(layer "B.SilkS")
		)
		(fp_poly
			(pts
				(xy 0.508 0.2794) (xy 0.508 0.2286) (xy 0.635 0.2286) (xy 0.635 -0.254) (xy 0.5334 -0.254) (xy 0.5334 -0.2794)
				(xy -0.5334 -0.2794) (xy -0.5334 -0.254) (xy -0.635 -0.254) (xy -0.635 0.254) (xy -0.5334 0.254)
				(xy -0.5334 0.2794)
			)
			(stroke
				(width 0)
				(type default)
			)
			(fill no)
			(layer "B.CrtYd")
		)
		(pad "1" smd rect
			(at -0.40005 0)
			(size 0.4572 0.508)
			(layers "B.Cu" "B.Mask" "B.Paste")
			(net "P1V5_NODE1")
		)
		(pad "2" smd rect
			(at 0.40005 0)
			(size 0.4572 0.508)
			(layers "B.Cu" "B.Mask" "B.Paste")
			(net "P1V5_NODE1_AA21")
		)
	)
	(footprint ""
		(layer "B.Cu")
		(at 154.620214 -64.971422 -90)
		(property "Reference" "C343"
			(at 2.01422 -5.839714 270)
			(unlocked yes)
			(layer "B.SilkS")
			(effects
				(font
					(size 0.7874 0.5842)
					(thickness 0.1524)
				)
				(justify left mirror)
			)
		)
		(property "Value" ""
			(at 0 0 90)
			(layer "B.Fab")
			(effects
				(font
					(size 1.27 1.27)
				)
				(justify mirror)
			)
		)
		(duplicate_pad_numbers_are_jumpers no)
		(fp_line
			(start -0.7874 0.4064)
			(end 0.7874 0.4064)
			(stroke
				(width 0.1524)
				(type default)
			)
			(layer "B.SilkS")
		)
		(fp_line
			(start 0.7874 0.4064)
			(end 0.7874 -0.4064)
			(stroke
				(width 0.1524)
				(type default)
			)
			(layer "B.SilkS")
		)
		(fp_line
			(start 0 0.381)
			(end 0 -0.381)
			(stroke
				(width 0.1524)
				(type default)
			)
			(layer "B.SilkS")
		)
		(fp_line
			(start -0.7874 -0.4064)
			(end -0.7874 0.4064)
			(stroke
				(width 0.1524)
				(type default)
			)
			(layer "B.SilkS")
		)
		(fp_line
			(start 0.7874 -0.4064)
			(end -0.7874 -0.4064)
			(stroke
				(width 0.1524)
				(type default)
			)
			(layer "B.SilkS")
		)
		(fp_poly
			(pts
				(xy 0.5334 0.254) (xy 0.635 0.254) (xy 0.635 0.2286) (xy 0.635 -0.254) (xy 0.5334 -0.254) (xy 0.5334 -0.2794)
				(xy -0.5334 -0.2794) (xy -0.5334 -0.254) (xy -0.635 -0.254) (xy -0.635 0.254) (xy -0.5334 0.254)
				(xy -0.5334 0.2794) (xy 0.508 0.2794) (xy 0.5334 0.2794)
			)
			(stroke
				(width 0)
				(type default)
			)
			(fill no)
			(layer "B.CrtYd")
		)
		(pad "1" smd rect
			(at -0.40005 0 90)
			(size 0.4572 0.508)
			(layers "B.Cu" "B.Mask" "B.Paste")
			(net "P1V8_SATA_VAA2_0_NODE1")
		)
		(pad "2" smd rect
			(at 0.40005 0 90)
			(size 0.4572 0.508)
			(layers "B.Cu" "B.Mask" "B.Paste")
			(net "GND")
		)
	)
	(footprint ""
		(layer "B.Cu")
		(at 128.912112 -144.83461 90)
		(property "Reference" "C931"
			(at 0.07112 2.44983 270)
			(unlocked yes)
			(layer "B.SilkS")
			(effects
				(font
					(size 0.7874 0.5842)
					(thickness 0.1524)
				)
				(justify left mirror)
			)
		)
		(property "Value" ""
			(at 0 0 90)
			(layer "B.Fab")
			(effects
				(font
					(size 1.27 1.27)
				)
				(justify mirror)
			)
		)
		(duplicate_pad_numbers_are_jumpers no)
		(fp_line
			(start 0.7874 -0.4064)
			(end -0.7874 -0.4064)
			(stroke
				(width 0.1524)
				(type default)
			)
			(layer "B.SilkS")
		)
		(fp_line
			(start -0.7874 -0.4064)
			(end -0.7874 0.4064)
			(stroke
				(width 0.1524)
				(type default)
			)
			(layer "B.SilkS")
		)
		(fp_line
			(start 0 0.381)
			(end 0 -0.381)
			(stroke
				(width 0.1524)
				(type default)
			)
			(layer "B.SilkS")
		)
		(fp_line
			(start 0.7874 0.4064)
			(end 0.7874 -0.4064)
			(stroke
				(width 0.1524)
				(type default)
			)
			(layer "B.SilkS")
		)
		(fp_line
			(start -0.7874 0.4064)
			(end 0.7874 0.4064)
			(stroke
				(width 0.1524)
				(type default)
			)
			(layer "B.SilkS")
		)
		(fp_poly
			(pts
				(xy 0.5334 0.254) (xy 0.635 0.254) (xy 0.635 0.2286) (xy 0.635 -0.254) (xy 0.5334 -0.254) (xy 0.5334 -0.2794)
				(xy -0.5334 -0.2794) (xy -0.5334 -0.254) (xy -0.635 -0.254) (xy -0.635 0.254) (xy -0.5334 0.254)
				(xy -0.5334 0.2794) (xy 0.508 0.2794) (xy 0.5334 0.2794)
			)
			(stroke
				(width 0)
				(type default)
			)
			(fill no)
			(layer "B.CrtYd")
		)
		(pad "1" smd rect
			(at -0.40005 0 270)
			(size 0.4572 0.508)
			(layers "B.Cu" "B.Mask" "B.Paste")
			(net "P1V0_PCI_SW_A")
		)
		(pad "2" smd rect
			(at 0.40005 0 270)
			(size 0.4572 0.508)
			(layers "B.Cu" "B.Mask" "B.Paste")
			(net "GND")
		)
	)
)
